(kicad_pcb
	(version 20260206)
	(generator "pcbnew")
	(generator_version "10.0")
	(general
		(thickness 1.6)
		(legacy_teardrops no)
	)
	(paper "A4")
	(title_block
		(title "panther-plus-userver — 13130-1b_20150205.brd")
		(comment 1 "Honey Badger (Wiwynn) / footprints 1360-1365 of 1509")
	)
	(layers
		(0 "F.Cu" signal "TOP")
		(4 "In1.Cu" signal "L2")
		(6 "In2.Cu" signal "L3")
		(8 "In3.Cu" signal "L4")
		(10 "In4.Cu" signal "L5")
		(12 "In5.Cu" signal "L6")
		(14 "In6.Cu" signal "L7")
		(16 "In7.Cu" signal "L8")
		(18 "In8.Cu" signal "L9")
		(20 "In9.Cu" signal "L10")
		(22 "In10.Cu" signal "L11")
		(2 "B.Cu" signal "BOTTOM")
		(9 "F.Adhes" user "F.Adhesive")
		(11 "B.Adhes" user "B.Adhesive")
		(13 "F.Paste" user "Package Geometry/Pastemask Top")
		(15 "B.Paste" user "Package Geometry/Pastemask Bottom")
		(5 "F.SilkS" user "Ref Des/Silkscreen Top")
		(7 "B.SilkS" user "Ref Des/Silkscreen Bottom")
		(1 "F.Mask" user "Board Geometry/Soldermask Top")
		(3 "B.Mask" user "Board Geometry/Soldermask Bottom")
		(17 "Dwgs.User" user "User.Drawings")
		(19 "Cmts.User" user "User.Comments")
		(21 "Eco1.User" user "User.Eco1")
		(23 "Eco2.User" user "User.Eco2")
		(25 "Edge.Cuts" user "Board Geometry/Outline")
		(27 "Margin" user)
		(31 "F.CrtYd" user "Package Geometry/Place Bound Top")
		(29 "B.CrtYd" user "Package Geometry/Place Bound Bottom")
		(35 "F.Fab" user "Ref Des/Assembly Top")
		(33 "B.Fab" user "Ref Des/Assembly Bottom")
	)
	(footprint ""
		(layer "B.Cu")
		(at 102.372668 -42.957496 90)
		(property "Reference" "C166"
			(at 0 0 90)
			(layer "B.SilkS")
			(hide yes)
			(effects
				(font
					(size 1.27 1.27)
				)
				(justify mirror)
			)
		)
		(property "Value" "SC1U10V2KX-1GP"
			(at -1.1811 -2.7051 90)
			(unlocked yes)
			(layer "B.Fab")
			(hide yes)
			(effects
				(font
					(size 1.016 1.016)
					(thickness 0.1524)
				)
				(justify mirror)
			)
		)
		(property "Device Type" "C402H22"
			(at -1.1811 -4.2291 90)
			(unlocked yes)
			(layer "B.Fab")
			(hide yes)
			(effects
				(font
					(size 1.016 1.016)
					(thickness 0.1524)
				)
				(justify mirror)
			)
		)
		(duplicate_pad_numbers_are_jumpers no)
		(fp_rect
			(start 0.381 0.7366)
			(end -0.381 -0.7366)
			(stroke
				(width 0)
				(type default)
			)
			(fill no)
			(layer "B.CrtYd")
		)
		(fp_rect
			(start 0.381 0.7366)
			(end -0.381 -0.7366)
			(stroke
				(width 0)
				(type default)
			)
			(fill no)
			(layer "B.Fab")
		)
		(pad "1" smd custom
			(at 0 -0.4572 270)
			(size 0.1143 0.1143)
			(layers "B.Cu" "B.Mask" "B.Paste")
			(net "P1V0")
			(options
				(clearance outline)
				(anchor circle)
			)
			(primitives
				(gr_poly
					(pts
						(arc
							(start -0.254 0.1778)
							(mid -0.239121 0.213721)
							(end -0.2032 0.2286)
						)
						(arc
							(start 0.2032 0.2286)
							(mid 0.239121 0.213721)
							(end 0.254 0.1778)
						)
						(arc
							(start 0.254 -0.1778)
							(mid 0.239121 -0.213721)
							(end 0.2032 -0.2286)
						)
						(arc
							(start -0.2032 -0.2286)
							(mid -0.239121 -0.213721)
							(end -0.254 -0.1778)
						)
					)
					(width 0)
					(fill yes)
				)
			)
		)
		(pad "2" smd custom
			(at 0 0.4572 270)
			(size 0.1143 0.1143)
			(layers "B.Cu" "B.Mask" "B.Paste")
			(net "GND")
			(options
				(clearance outline)
				(anchor circle)
			)
			(primitives
				(gr_poly
					(pts
						(arc
							(start -0.254 0.1778)
							(mid -0.239121 0.213721)
							(end -0.2032 0.2286)
						)
						(arc
							(start 0.2032 0.2286)
							(mid 0.239121 0.213721)
							(end 0.254 0.1778)
						)
						(arc
							(start 0.254 -0.1778)
							(mid 0.239121 -0.213721)
							(end 0.2032 -0.2286)
						)
						(arc
							(start -0.2032 -0.2286)
							(mid -0.239121 -0.213721)
							(end -0.254 -0.1778)
						)
					)
					(width 0)
					(fill yes)
				)
			)
		)
	)
	(footprint ""
		(layer "B.Cu")
		(at 98.282252 -37.229288 -90)
		(property "Reference" "TP32"
			(at 0 0 90)
			(layer "B.SilkS")
			(hide yes)
			(effects
				(font
					(size 1.27 1.27)
				)
				(justify mirror)
			)
		)
		(property "Value" "TPAD24"
			(at 0 -2.9972 270)
			(unlocked yes)
			(layer "B.Fab")
			(hide yes)
			(effects
				(font
					(size 1.016 1.016)
					(thickness 0.1524)
				)
				(justify mirror)
			)
		)
		(property "Device Type" "TPAD24"
			(at 0 -4.5212 270)
			(unlocked yes)
			(layer "B.Fab")
			(hide yes)
			(effects
				(font
					(size 1.016 1.016)
					(thickness 0.1524)
				)
				(justify mirror)
			)
		)
		(duplicate_pad_numbers_are_jumpers no)
		(fp_poly
			(pts
				(arc
					(start 0 -0.3048)
					(mid 0 0.3048)
					(end 0 -0.3048)
				)
			)
			(stroke
				(width 0)
				(type default)
			)
			(fill no)
			(layer "B.CrtYd")
		)
		(fp_poly
			(pts
				(arc
					(start 0 -0.6096)
					(mid 0 0.6096)
					(end 0 -0.6096)
				)
			)
			(stroke
				(width 0)
				(type default)
			)
			(fill no)
			(layer "B.Fab")
		)
		(pad "1" smd circle
			(at 0 0 90)
			(size 0.6096 0.6096)
			(layers "B.Cu" "B.Mask" "B.Paste")
			(net "TP_CPU_RSVD11")
		)
	)
	(footprint ""
		(layer "B.Cu")
		(at 45.858684 -48.897286 90)
		(property "Reference" "U16"
			(at 0 0 90)
			(layer "B.SilkS")
			(hide yes)
			(effects
				(font
					(size 1.27 1.27)
				)
				(justify mirror)
			)
		)
		(property "Value" "9VRS4420DKLFT-GP"
			(at 0.381 -13.7668 90)
			(unlocked yes)
			(layer "B.Fab")
			(hide yes)
			(effects
				(font
					(size 1.016 1.016)
					(thickness 0.1524)
				)
				(justify mirror)
			)
		)
		(property "Device Type" "QFN48J6-G4D3-UH40"
			(at 0.381 -15.2908 90)
			(unlocked yes)
			(layer "B.Fab")
			(hide yes)
			(effects
				(font
					(size 1.016 1.016)
					(thickness 0.1524)
				)
				(justify mirror)
			)
		)
		(duplicate_pad_numbers_are_jumpers no)
		(fp_poly
			(pts
				(xy -3.3909 -3.3909) (xy -2.4638 -3.3909) (xy -3.3909 -2.4638)
			)
			(stroke
				(width 0)
				(type default)
			)
			(fill yes)
			(layer "B.SilkS")
		)
		(fp_rect
			(start 3.3909 3.3909)
			(end -3.3909 -3.3909)
			(stroke
				(width 0)
				(type default)
			)
			(fill no)
			(layer "B.CrtYd")
		)
		(fp_rect
			(start 3.3909 3.3909)
			(end -3.3909 -3.3909)
			(stroke
				(width 0)
				(type default)
			)
			(fill no)
			(layer "B.Fab")
		)
		(pad "1" smd rect
			(at -2.199894 -2.809494 270)
			(size 0.2032 0.6858)
			(drill
				(offset 0 0.1016)
			)
			(layers "B.Cu" "B.Mask" "B.Paste")
			(net "XTAL_CLK_GEN_OUT_R")
		)
		(pad "2" smd rect
			(at -1.800098 -2.809494 270)
			(size 0.2032 0.889)
			(layers "B.Cu" "B.Mask" "B.Paste")
			(net "XTAL_CLK_GEN_IN")
		)
		(pad "3" smd rect
			(at -1.400048 -2.809494 270)
			(size 0.2032 0.889)
			(layers "B.Cu" "B.Mask" "B.Paste")
			(net "P3V3_CLK_XTAL")
		)
		(pad "4" smd rect
			(at -0.999998 -2.809494 270)
			(size 0.2032 0.889)
			(layers "B.Cu" "B.Mask" "B.Paste")
			(net "CLK_14M_CPU_R")
		)
		(pad "5" smd rect
			(at -0.599948 -2.809494 270)
			(size 0.2032 0.889)
			(layers "B.Cu" "B.Mask" "B.Paste")
			(net "SMB_CLKGEN_R_DATA")
		)
		(pad "6" smd rect
			(at -0.199898 -2.809494 270)
			(size 0.2032 0.889)
			(layers "B.Cu" "B.Mask" "B.Paste")
			(net "SMB_CLKGEN_R_CLK")
		)
		(pad "7" smd rect
			(at 0.199898 -2.809494 270)
			(size 0.2032 0.889)
			(layers "B.Cu" "B.Mask" "B.Paste")
			(net "P3V3_CLK_PCI")
		)
		(pad "8" smd rect
			(at 0.599948 -2.809494 270)
			(size 0.2032 0.889)
			(layers "B.Cu" "B.Mask" "B.Paste")
			(net "Net_71")
		)
		(pad "9" smd rect
			(at 0.999998 -2.809494 270)
			(size 0.2032 0.889)
			(layers "B.Cu" "B.Mask" "B.Paste")
			(net "Net_70")
		)
		(pad "10" smd rect
			(at 1.400048 -2.809494 270)
			(size 0.2032 0.889)
			(layers "B.Cu" "B.Mask" "B.Paste")
			(net "Net_69")
		)
		(pad "11" smd rect
			(at 1.800098 -2.809494 270)
			(size 0.2032 0.889)
			(layers "B.Cu" "B.Mask" "B.Paste")
			(net "GND")
		)
		(pad "12" smd rect
			(at 2.199894 -2.809494 270)
			(size 0.2032 0.6858)
			(drill
				(offset 0 0.1016)
			)
			(layers "B.Cu" "B.Mask" "B.Paste")
			(net "GND")
		)
		(pad "13" smd rect
			(at 2.809494 -2.199894 270)
			(size 0.6858 0.2032)
			(drill
				(offset -0.1016 0)
			)
			(layers "B.Cu" "B.Mask" "B.Paste")
			(net "CLKGEN_VSEL_PCI")
		)
		(pad "14" smd rect
			(at 2.809494 -1.800098 270)
			(size 0.889 0.2032)
			(layers "B.Cu" "B.Mask" "B.Paste")
			(net "P3V3_CLK_VDD25")
		)
		(pad "15" smd rect
			(at 2.809494 -1.400048 270)
			(size 0.889 0.2032)
			(layers "B.Cu" "B.Mask" "B.Paste")
			(net "P3V3_CLK_VDD25")
		)
		(pad "16" smd rect
			(at 2.809494 -0.999998 270)
			(size 0.889 0.2032)
			(layers "B.Cu" "B.Mask" "B.Paste")
			(net "Net_72")
		)
		(pad "17" smd rect
			(at 2.809494 -0.599948 270)
			(size 0.889 0.2032)
			(layers "B.Cu" "B.Mask" "B.Paste")
			(net "GND")
		)
		(pad "18" smd rect
			(at 2.809494 -0.199898 270)
			(size 0.889 0.2032)
			(layers "B.Cu" "B.Mask" "B.Paste")
			(net "CLKREQB")
		)
		(pad "19" smd rect
			(at 2.809494 0.199898 270)
			(size 0.889 0.2032)
			(layers "B.Cu" "B.Mask" "B.Paste")
			(net "CLK_96M_CPU_USB_DP")
		)
		(pad "20" smd rect
			(at 2.809494 0.599948 270)
			(size 0.889 0.2032)
			(layers "B.Cu" "B.Mask" "B.Paste")
			(net "CLK_96M_CPU_USB_DN")
		)
		(pad "21" smd rect
			(at 2.809494 0.999998 270)
			(size 0.889 0.2032)
			(layers "B.Cu" "B.Mask" "B.Paste")
			(net "P1V5_CLK_VDD_CORE")
		)
		(pad "22" smd rect
			(at 2.809494 1.400048 270)
			(size 0.889 0.2032)
			(layers "B.Cu" "B.Mask" "B.Paste")
			(net "CLK_100M_CPU_SATA3_DP")
		)
		(pad "23" smd rect
			(at 2.809494 1.800098 270)
			(size 0.889 0.2032)
			(layers "B.Cu" "B.Mask" "B.Paste")
			(net "CLK_100M_CPU_SATA3_DN")
		)
		(pad "24" smd rect
			(at 2.809494 2.199894 270)
			(size 0.6858 0.2032)
			(drill
				(offset -0.1016 0)
			)
			(layers "B.Cu" "B.Mask" "B.Paste")
			(net "GND")
		)
		(pad "25" smd rect
			(at 2.199894 2.809494 270)
			(size 0.2032 0.6858)
			(drill
				(offset 0 -0.1016)
			)
			(layers "B.Cu" "B.Mask" "B.Paste")
			(net "GND")
		)
		(pad "26" smd rect
			(at 1.800098 2.809494 270)
			(size 0.2032 0.889)
			(layers "B.Cu" "B.Mask" "B.Paste")
			(net "CLK_100M_CLKBUFF_DN")
		)
		(pad "27" smd rect
			(at 1.400048 2.809494 270)
			(size 0.2032 0.889)
			(layers "B.Cu" "B.Mask" "B.Paste")
			(net "CLK_100M_CLKBUFF_DP")
		)
		(pad "28" smd rect
			(at 0.999998 2.809494 270)
			(size 0.2032 0.889)
			(layers "B.Cu" "B.Mask" "B.Paste")
			(net "CLK_100M_CPU_MPLL1_DN")
		)
		(pad "29" smd rect
			(at 0.599948 2.809494 270)
			(size 0.2032 0.889)
			(layers "B.Cu" "B.Mask" "B.Paste")
			(net "CLK_100M_CPU_MPLL1_DP")
		)
		(pad "30" smd rect
			(at 0.199898 2.809494 270)
			(size 0.2032 0.889)
			(layers "B.Cu" "B.Mask" "B.Paste")
			(net "P1V5_CLK_SCR_LVIO")
		)
		(pad "31" smd rect
			(at -0.199898 2.809494 270)
			(size 0.2032 0.889)
			(layers "B.Cu" "B.Mask" "B.Paste")
			(net "CLKGEN_PCI_STOP#")
		)
		(pad "32" smd rect
			(at -0.599948 2.809494 270)
			(size 0.2032 0.889)
			(layers "B.Cu" "B.Mask" "B.Paste")
			(net "CLK_100M_CPU_MPLL0_DN")
		)
		(pad "33" smd rect
			(at -0.999998 2.809494 270)
			(size 0.2032 0.889)
			(layers "B.Cu" "B.Mask" "B.Paste")
			(net "CLK_100M_CPU_MPLL0_DP")
		)
		(pad "34" smd rect
			(at -1.400048 2.809494 270)
			(size 0.2032 0.889)
			(layers "B.Cu" "B.Mask" "B.Paste")
			(net "GND")
		)
		(pad "35" smd rect
			(at -1.800098 2.809494 270)
			(size 0.2032 0.889)
			(layers "B.Cu" "B.Mask" "B.Paste")
			(net "CLK_100M_CPU_HFHPLL_DN")
		)
		(pad "36" smd rect
			(at -2.199894 2.809494 270)
			(size 0.2032 0.6858)
			(drill
				(offset 0 -0.1016)
			)
			(layers "B.Cu" "B.Mask" "B.Paste")
			(net "CLK_100M_CPU_HFHPLL_DP")
		)
		(pad "37" smd rect
			(at -2.809494 2.199894 270)
			(size 0.6858 0.2032)
			(drill
				(offset 0.1016 0)
			)
			(layers "B.Cu" "B.Mask" "B.Paste")
			(net "CLKGEN_DIF_STOP#")
		)
		(pad "38" smd rect
			(at -2.809494 1.800098 270)
			(size 0.889 0.2032)
			(layers "B.Cu" "B.Mask" "B.Paste")
			(net "CLK_100M_XDP_R_DN")
		)
		(pad "39" smd rect
			(at -2.809494 1.400048 270)
			(size 0.889 0.2032)
			(layers "B.Cu" "B.Mask" "B.Paste")
			(net "CLK_100M_XDP_R_DP")
		)
		(pad "40" smd rect
			(at -2.809494 0.999998 270)
			(size 0.889 0.2032)
			(layers "B.Cu" "B.Mask" "B.Paste")
			(net "P1V5_CLK_VDD_CORE")
		)
		(pad "41" smd rect
			(at -2.809494 0.599948 270)
			(size 0.889 0.2032)
			(layers "B.Cu" "B.Mask" "B.Paste")
			(net "P1V5_CLK_VDDDIF")
		)
		(pad "42" smd rect
			(at -2.809494 0.199898 270)
			(size 0.889 0.2032)
			(layers "B.Cu" "B.Mask" "B.Paste")
			(net "CLK_100M_SATA2_DN")
		)
		(pad "43" smd rect
			(at -2.809494 -0.199898 270)
			(size 0.889 0.2032)
			(layers "B.Cu" "B.Mask" "B.Paste")
			(net "CLK_100M_SATA2_DP")
		)
		(pad "44" smd rect
			(at -2.809494 -0.599948 270)
			(size 0.889 0.2032)
			(layers "B.Cu" "B.Mask" "B.Paste")
			(net "GND")
		)
		(pad "45" smd rect
			(at -2.809494 -0.999998 270)
			(size 0.889 0.2032)
			(layers "B.Cu" "B.Mask" "B.Paste")
			(net "CLK_100M_CPU_GBE_DN")
		)
		(pad "46" smd rect
			(at -2.809494 -1.400048 270)
			(size 0.889 0.2032)
			(layers "B.Cu" "B.Mask" "B.Paste")
			(net "CLK_100M_CPU_GBE_DP")
		)
		(pad "47" smd rect
			(at -2.809494 -1.800098 270)
			(size 0.889 0.2032)
			(layers "B.Cu" "B.Mask" "B.Paste")
			(net "CLK_GEN_R_PG")
		)
		(pad "48" smd rect
			(at -2.809494 -2.199894 270)
			(size 0.6858 0.2032)
			(drill
				(offset 0.1016 0)
			)
			(layers "B.Cu" "B.Mask" "B.Paste")
			(net "GND")
		)
		(pad "49" smd rect
			(at 0 0 270)
			(size 4.2926 4.2926)
			(layers "B.Cu" "B.Mask" "B.Paste")
			(net "GND")
		)
	)
	(footprint ""
		(layer "B.Cu")
		(at 203.4794 -58.2676 90)
		(property "Reference" "PC166"
			(at 0 0 90)
			(layer "B.SilkS")
			(hide yes)
			(effects
				(font
					(size 1.27 1.27)
				)
				(justify mirror)
			)
		)
		(property "Value" "SC22U6D3V5MX-2GP"
			(at 0 -4.9022 90)
			(unlocked yes)
			(layer "B.Fab")
			(hide yes)
			(effects
				(font
					(size 1.016 1.016)
					(thickness 0.1524)
				)
				(justify mirror)
			)
		)
		(property "Device Type" "C805H58"
			(at 0 -6.8072 90)
			(unlocked yes)
			(layer "B.Fab")
			(hide yes)
			(effects
				(font
					(size 1.016 1.016)
					(thickness 0.1524)
				)
				(justify mirror)
			)
		)
		(duplicate_pad_numbers_are_jumpers no)
		(fp_line
			(start -0.6096 0)
			(end 0.6096 0)
			(stroke
				(width 0.3048)
				(type default)
			)
			(layer "B.SilkS")
		)
		(fp_poly
			(pts
				(xy 0.9017 1.4351) (xy -0.9017 1.4351) (xy -0.9017 -1.4351) (xy 0.9017 -1.4351)
			)
			(stroke
				(width 0)
				(type default)
			)
			(fill no)
			(layer "B.CrtYd")
		)
		(fp_poly
			(pts
				(xy -0.9017 1.4351) (xy -0.9017 -1.4351) (xy 0.9017 -1.4351) (xy 0.9017 1.4351)
			)
			(stroke
				(width 0)
				(type default)
			)
			(fill no)
			(layer "B.Fab")
		)
		(pad "1" smd rect
			(at 0 -0.8382 270)
			(size 1.5494 0.9398)
			(layers "B.Cu" "B.Mask" "B.Paste")
			(net "PV_VDDR")
		)
		(pad "2" smd rect
			(at 0 0.8382 270)
			(size 1.5494 0.9398)
			(layers "B.Cu" "B.Mask" "B.Paste")
			(net "GND")
		)
	)
	(footprint ""
		(layer "B.Cu")
		(at 42.926 -15.5702 -90)
		(property "Reference" "R428"
			(at 0 0 90)
			(layer "B.SilkS")
			(hide yes)
			(effects
				(font
					(size 1.27 1.27)
				)
				(justify mirror)
			)
		)
		(property "Value" "43D2R2F-GP"
			(at -1.7907 -1.1176 270)
			(unlocked yes)
			(layer "B.Fab")
			(hide yes)
			(effects
				(font
					(size 1.016 1.016)
					(thickness 0.1524)
				)
				(justify mirror)
			)
		)
		(property "Device Type" "R402H16"
			(at -1.7907 -2.6416 270)
			(unlocked yes)
			(layer "B.Fab")
			(hide yes)
			(effects
				(font
					(size 1.016 1.016)
					(thickness 0.1524)
				)
				(justify mirror)
			)
		)
		(duplicate_pad_numbers_are_jumpers no)
		(fp_rect
			(start 0.381 0.8382)
			(end -0.381 -0.8382)
			(stroke
				(width 0)
				(type default)
			)
			(fill no)
			(layer "B.CrtYd")
		)
		(fp_rect
			(start 0.381 0.8382)
			(end -0.381 -0.8382)
			(stroke
				(width 0)
				(type default)
			)
			(fill no)
			(layer "B.Fab")
		)
		(pad "1" smd custom
			(at 0 -0.4318 90)
			(size 0.127 0.127)
			(layers "B.Cu" "B.Mask" "B.Paste")
			(net "CLK_100M_CLKBUFF_ENET_DN")
			(options
				(clearance outline)
				(anchor circle)
			)
			(primitives
				(gr_poly
					(pts
						(arc
							(start -0.2032 0.2794)
							(mid -0.239121 0.264521)
							(end -0.254 0.2286)
						)
						(arc
							(start -0.254 -0.2286)
							(mid -0.239121 -0.264521)
							(end -0.2032 -0.2794)
						)
						(arc
							(start 0.2032 -0.2794)
							(mid 0.239121 -0.264521)
							(end 0.254 -0.2286)
						)
						(arc
							(start 0.254 0.2286)
							(mid 0.239121 0.264521)
							(end 0.2032 0.2794)
						)
					)
					(width 0)
					(fill yes)
				)
			)
		)
		(pad "2" smd custom
			(at 0 0.4318 90)
			(size 0.127 0.127)
			(layers "B.Cu" "B.Mask" "B.Paste")
			(net "GND")
			(options
				(clearance outline)
				(anchor circle)
			)
			(primitives
				(gr_poly
					(pts
						(arc
							(start -0.2032 0.2794)
							(mid -0.239121 0.264521)
							(end -0.254 0.2286)
						)
						(arc
							(start -0.254 -0.2286)
							(mid -0.239121 -0.264521)
							(end -0.2032 -0.2794)
						)
						(arc
							(start 0.2032 -0.2794)
							(mid 0.239121 -0.264521)
							(end 0.254 -0.2286)
						)
						(arc
							(start 0.254 0.2286)
							(mid 0.239121 0.264521)
							(end 0.2032 0.2794)
						)
					)
					(width 0)
					(fill yes)
				)
			)
		)
	)
	(footprint ""
		(layer "B.Cu")
		(at 111.7346 -45.466 180)
		(property "Reference" "C188"
			(at 0 0 0)
			(layer "B.SilkS")
			(hide yes)
			(effects
				(font
					(size 1.27 1.27)
				)
				(justify mirror)
			)
		)
		(property "Value" "SC22U6D3V5MX-2GP"
			(at 0.0762 -6.1214 180)
			(unlocked yes)
			(layer "B.Fab")
			(hide yes)
			(effects
				(font
					(size 1.016 1.016)
					(thickness 0.1524)
				)
				(justify mirror)
			)
		)
		(property "Device Type" "C805H58"
			(at 0.0762 -8.1534 180)
			(unlocked yes)
			(layer "B.Fab")
			(hide yes)
			(effects
				(font
					(size 1.016 1.016)
					(thickness 0.1524)
				)
				(justify mirror)
			)
		)
		(duplicate_pad_numbers_are_jumpers no)
		(fp_line
			(start -0.6096 0)
			(end 0.6096 0)
			(stroke
				(width 0.3048)
				(type default)
			)
			(layer "B.SilkS")
		)
		(fp_poly
			(pts
				(xy 0.9017 1.4351) (xy -0.9017 1.4351) (xy -0.9017 -1.4351) (xy 0.9017 -1.4351)
			)
			(stroke
				(width 0)
				(type default)
			)
			(fill no)
			(layer "B.CrtYd")
		)
		(fp_poly
			(pts
				(xy -0.9017 1.4351) (xy -0.9017 -1.4351) (xy 0.9017 -1.4351) (xy 0.9017 1.4351)
			)
			(stroke
				(width 0)
				(type default)
			)
			(fill no)
			(layer "B.Fab")
		)
		(pad "1" smd rect
			(at 0 -0.8382)
			(size 1.5494 0.9398)
			(layers "B.Cu" "B.Mask" "B.Paste")
			(net "PVCCP")
		)
		(pad "2" smd rect
			(at 0 0.8382)
			(size 1.5494 0.9398)
			(layers "B.Cu" "B.Mask" "B.Paste")
			(net "GND")
		)
	)
)
